G04 #@! TF.GenerationSoftware,KiCad,Pcbnew,(5.0.1)-3*
G04 #@! TF.CreationDate,2019-04-10T15:36:06+02:00*
G04 #@! TF.ProjectId,discovery,646973636F766572792E6B696361645F,rev?*
G04 #@! TF.SameCoordinates,PX4c4640PY8a48028*
G04 #@! TF.FileFunction,Soldermask,Top*
G04 #@! TF.FilePolarity,Negative*
%FSLAX46Y46*%
G04 Gerber Fmt 4.6, Leading zero omitted, Abs format (unit mm)*
%MOMM*%
%LPD*%
G01*
G04 APERTURE LIST*
%ADD10C,0.100000*%
G04 APERTURE END LIST*
D10*
G36*
X140745376Y2451407D02*
X140745378Y2451406D01*
X140745379Y2451406D01*
X141209632Y2259107D01*
X141625564Y1981190D01*
X141627451Y1979929D01*
X141982769Y1624611D01*
X141982771Y1624608D01*
X142261947Y1206792D01*
X142454246Y742539D01*
X142552280Y249692D01*
X142552280Y-252812D01*
X142454246Y-745659D01*
X142261947Y-1209912D01*
X141984030Y-1625844D01*
X141982769Y-1627731D01*
X141627451Y-1983049D01*
X141627448Y-1983051D01*
X141209632Y-2262227D01*
X140745379Y-2454526D01*
X140745378Y-2454526D01*
X140745376Y-2454527D01*
X140252533Y-2552560D01*
X139750027Y-2552560D01*
X139257184Y-2454527D01*
X139257182Y-2454526D01*
X139257181Y-2454526D01*
X138792928Y-2262227D01*
X138375112Y-1983051D01*
X138375109Y-1983049D01*
X138019791Y-1627731D01*
X138018530Y-1625844D01*
X137740613Y-1209912D01*
X137548314Y-745659D01*
X137450280Y-252812D01*
X137450280Y249692D01*
X137548314Y742539D01*
X137740613Y1206792D01*
X138019789Y1624608D01*
X138019791Y1624611D01*
X138375109Y1979929D01*
X138376996Y1981190D01*
X138792928Y2259107D01*
X139257181Y2451406D01*
X139257182Y2451406D01*
X139257184Y2451407D01*
X139750027Y2549440D01*
X140252533Y2549440D01*
X140745376Y2451407D01*
X140745376Y2451407D01*
G37*
G36*
X745376Y2451407D02*
X745378Y2451406D01*
X745379Y2451406D01*
X1209632Y2259107D01*
X1625564Y1981190D01*
X1627451Y1979929D01*
X1982769Y1624611D01*
X1982771Y1624608D01*
X2261947Y1206792D01*
X2454246Y742539D01*
X2552280Y249692D01*
X2552280Y-252812D01*
X2454246Y-745659D01*
X2261947Y-1209912D01*
X1984030Y-1625844D01*
X1982769Y-1627731D01*
X1627451Y-1983049D01*
X1627448Y-1983051D01*
X1209632Y-2262227D01*
X745379Y-2454526D01*
X745378Y-2454526D01*
X745376Y-2454527D01*
X252533Y-2552560D01*
X-249973Y-2552560D01*
X-742816Y-2454527D01*
X-742818Y-2454526D01*
X-742819Y-2454526D01*
X-1207072Y-2262227D01*
X-1624888Y-1983051D01*
X-1624891Y-1983049D01*
X-1980209Y-1627731D01*
X-1981470Y-1625844D01*
X-2259387Y-1209912D01*
X-2451686Y-745659D01*
X-2549720Y-252812D01*
X-2549720Y249692D01*
X-2451686Y742539D01*
X-2259387Y1206792D01*
X-1980211Y1624608D01*
X-1980209Y1624611D01*
X-1624891Y1979929D01*
X-1623004Y1981190D01*
X-1207072Y2259107D01*
X-742819Y2451406D01*
X-742818Y2451406D01*
X-742816Y2451407D01*
X-249973Y2549440D01*
X252533Y2549440D01*
X745376Y2451407D01*
X745376Y2451407D01*
G37*
G36*
X57203825Y17759260D02*
X58578018Y17190050D01*
X58578020Y17190049D01*
X59787209Y16382095D01*
X59814765Y16363683D01*
X60866523Y15311925D01*
X60866525Y15311922D01*
X61432527Y14464840D01*
X61692890Y14075178D01*
X62262100Y12700985D01*
X62552280Y11242150D01*
X62552280Y9754730D01*
X62262100Y8295895D01*
X61753425Y7067847D01*
X61692889Y6921700D01*
X61068758Y5987621D01*
X60866523Y5684955D01*
X59814765Y4633197D01*
X59814762Y4633195D01*
X58578020Y3806831D01*
X58578019Y3806830D01*
X58578018Y3806830D01*
X57203825Y3237620D01*
X55744990Y2947440D01*
X54257570Y2947440D01*
X52798735Y3237620D01*
X51424542Y3806830D01*
X51424541Y3806830D01*
X51424540Y3806831D01*
X50187798Y4633195D01*
X50187795Y4633197D01*
X49136037Y5684955D01*
X48933802Y5987621D01*
X48309671Y6921700D01*
X48249135Y7067847D01*
X47740460Y8295895D01*
X47450280Y9754730D01*
X47450280Y11242150D01*
X47740460Y12700985D01*
X48309670Y14075178D01*
X48570034Y14464840D01*
X49136035Y15311922D01*
X49136037Y15311925D01*
X50187795Y16363683D01*
X50215351Y16382095D01*
X51424540Y17190049D01*
X51424542Y17190050D01*
X52798735Y17759260D01*
X54257570Y18049440D01*
X55744990Y18049440D01*
X57203825Y17759260D01*
X57203825Y17759260D01*
G37*
G36*
X6499532Y8838022D02*
X6499534Y8838021D01*
X6499535Y8838021D01*
X6872793Y8683413D01*
X6872794Y8683412D01*
X7208719Y8458954D01*
X7494394Y8173279D01*
X7494396Y8173276D01*
X7718853Y7837353D01*
X7873461Y7464095D01*
X7952280Y7067846D01*
X7952280Y6663834D01*
X7873461Y6267585D01*
X7718853Y5894327D01*
X7718852Y5894326D01*
X7494394Y5558401D01*
X7208719Y5272726D01*
X7208716Y5272724D01*
X6872793Y5048267D01*
X6499535Y4893659D01*
X6499534Y4893659D01*
X6499532Y4893658D01*
X6103287Y4814840D01*
X5699273Y4814840D01*
X5303028Y4893658D01*
X5303026Y4893659D01*
X5303025Y4893659D01*
X4929767Y5048267D01*
X4593844Y5272724D01*
X4593841Y5272726D01*
X4308166Y5558401D01*
X4083708Y5894326D01*
X4083707Y5894327D01*
X3929099Y6267585D01*
X3850280Y6663834D01*
X3850280Y7067846D01*
X3929099Y7464095D01*
X4083707Y7837353D01*
X4308164Y8173276D01*
X4308166Y8173279D01*
X4593841Y8458954D01*
X4929766Y8683412D01*
X4929767Y8683413D01*
X5303025Y8838021D01*
X5303026Y8838021D01*
X5303028Y8838022D01*
X5699273Y8916840D01*
X6103287Y8916840D01*
X6499532Y8838022D01*
X6499532Y8838022D01*
G37*
G36*
X30699532Y8838022D02*
X30699534Y8838021D01*
X30699535Y8838021D01*
X31072793Y8683413D01*
X31072794Y8683412D01*
X31408719Y8458954D01*
X31694394Y8173279D01*
X31694396Y8173276D01*
X31918853Y7837353D01*
X32073461Y7464095D01*
X32152280Y7067846D01*
X32152280Y6663834D01*
X32073461Y6267585D01*
X31918853Y5894327D01*
X31918852Y5894326D01*
X31694394Y5558401D01*
X31408719Y5272726D01*
X31408716Y5272724D01*
X31072793Y5048267D01*
X30699535Y4893659D01*
X30699534Y4893659D01*
X30699532Y4893658D01*
X30303287Y4814840D01*
X29899273Y4814840D01*
X29503028Y4893658D01*
X29503026Y4893659D01*
X29503025Y4893659D01*
X29129767Y5048267D01*
X28793844Y5272724D01*
X28793841Y5272726D01*
X28508166Y5558401D01*
X28283708Y5894326D01*
X28283707Y5894327D01*
X28129099Y6267585D01*
X28050280Y6663834D01*
X28050280Y7067846D01*
X28129099Y7464095D01*
X28283707Y7837353D01*
X28508164Y8173276D01*
X28508166Y8173279D01*
X28793841Y8458954D01*
X29129766Y8683412D01*
X29129767Y8683413D01*
X29503025Y8838021D01*
X29503026Y8838021D01*
X29503028Y8838022D01*
X29899273Y8916840D01*
X30303287Y8916840D01*
X30699532Y8838022D01*
X30699532Y8838022D01*
G37*
G36*
X117203825Y20509260D02*
X118578018Y19940050D01*
X118578020Y19940049D01*
X119107361Y19586355D01*
X119814765Y19113683D01*
X120866523Y18061925D01*
X120866525Y18061922D01*
X121630354Y16918771D01*
X121692890Y16825178D01*
X122262100Y15450985D01*
X122552280Y13992150D01*
X122552280Y12504730D01*
X122262100Y11045895D01*
X121959285Y10314836D01*
X121692889Y9671700D01*
X120882560Y8458956D01*
X120866523Y8434955D01*
X119814765Y7383197D01*
X119814762Y7383195D01*
X118578020Y6556831D01*
X118578019Y6556830D01*
X118578018Y6556830D01*
X117203825Y5987620D01*
X115744990Y5697440D01*
X114257570Y5697440D01*
X112798735Y5987620D01*
X111424542Y6556830D01*
X111424541Y6556830D01*
X111424540Y6556831D01*
X110187798Y7383195D01*
X110187795Y7383197D01*
X109136037Y8434955D01*
X109120000Y8458956D01*
X108309671Y9671700D01*
X108043275Y10314836D01*
X107740460Y11045895D01*
X107450280Y12504730D01*
X107450280Y13992150D01*
X107740460Y15450985D01*
X108309670Y16825178D01*
X108372207Y16918771D01*
X109136035Y18061922D01*
X109136037Y18061925D01*
X110187795Y19113683D01*
X110895199Y19586355D01*
X111424540Y19940049D01*
X111424542Y19940050D01*
X112798735Y20509260D01*
X114257570Y20799440D01*
X115744990Y20799440D01*
X117203825Y20509260D01*
X117203825Y20509260D01*
G37*
G36*
X10480765Y12816844D02*
X10480767Y12816843D01*
X10480768Y12816843D01*
X10717535Y12718771D01*
X10930622Y12576391D01*
X11111831Y12395182D01*
X11254211Y12182095D01*
X11352284Y11945325D01*
X11402280Y11693979D01*
X11402280Y11437701D01*
X11352284Y11186355D01*
X11254211Y10949585D01*
X11111831Y10736498D01*
X10930622Y10555289D01*
X10930619Y10555287D01*
X10717535Y10412909D01*
X10480768Y10314837D01*
X10480767Y10314837D01*
X10480765Y10314836D01*
X10229419Y10264840D01*
X9973141Y10264840D01*
X9721795Y10314836D01*
X9721793Y10314837D01*
X9721792Y10314837D01*
X9485025Y10412909D01*
X9271941Y10555287D01*
X9271938Y10555289D01*
X9090729Y10736498D01*
X8948349Y10949585D01*
X8850276Y11186355D01*
X8800280Y11437701D01*
X8800280Y11693979D01*
X8850276Y11945325D01*
X8948349Y12182095D01*
X9090729Y12395182D01*
X9271938Y12576391D01*
X9485025Y12718771D01*
X9721792Y12816843D01*
X9721793Y12816843D01*
X9721795Y12816844D01*
X9973141Y12866840D01*
X10229419Y12866840D01*
X10480765Y12816844D01*
X10480765Y12816844D01*
G37*
G36*
X6280765Y12816844D02*
X6280767Y12816843D01*
X6280768Y12816843D01*
X6517535Y12718771D01*
X6730622Y12576391D01*
X6911831Y12395182D01*
X7054211Y12182095D01*
X7152284Y11945325D01*
X7202280Y11693979D01*
X7202280Y11437701D01*
X7152284Y11186355D01*
X7054211Y10949585D01*
X6911831Y10736498D01*
X6730622Y10555289D01*
X6730619Y10555287D01*
X6517535Y10412909D01*
X6280768Y10314837D01*
X6280767Y10314837D01*
X6280765Y10314836D01*
X6029419Y10264840D01*
X5773141Y10264840D01*
X5521795Y10314836D01*
X5521793Y10314837D01*
X5521792Y10314837D01*
X5285025Y10412909D01*
X5071941Y10555287D01*
X5071938Y10555289D01*
X4890729Y10736498D01*
X4748349Y10949585D01*
X4650276Y11186355D01*
X4600280Y11437701D01*
X4600280Y11693979D01*
X4650276Y11945325D01*
X4748349Y12182095D01*
X4890729Y12395182D01*
X5071938Y12576391D01*
X5285025Y12718771D01*
X5521792Y12816843D01*
X5521793Y12816843D01*
X5521795Y12816844D01*
X5773141Y12866840D01*
X6029419Y12866840D01*
X6280765Y12816844D01*
X6280765Y12816844D01*
G37*
G36*
X30480765Y12816844D02*
X30480767Y12816843D01*
X30480768Y12816843D01*
X30717535Y12718771D01*
X30930622Y12576391D01*
X31111831Y12395182D01*
X31254211Y12182095D01*
X31352284Y11945325D01*
X31402280Y11693979D01*
X31402280Y11437701D01*
X31352284Y11186355D01*
X31254211Y10949585D01*
X31111831Y10736498D01*
X30930622Y10555289D01*
X30930619Y10555287D01*
X30717535Y10412909D01*
X30480768Y10314837D01*
X30480767Y10314837D01*
X30480765Y10314836D01*
X30229419Y10264840D01*
X29973141Y10264840D01*
X29721795Y10314836D01*
X29721793Y10314837D01*
X29721792Y10314837D01*
X29485025Y10412909D01*
X29271941Y10555287D01*
X29271938Y10555289D01*
X29090729Y10736498D01*
X28948349Y10949585D01*
X28850276Y11186355D01*
X28800280Y11437701D01*
X28800280Y11693979D01*
X28850276Y11945325D01*
X28948349Y12182095D01*
X29090729Y12395182D01*
X29271938Y12576391D01*
X29485025Y12718771D01*
X29721792Y12816843D01*
X29721793Y12816843D01*
X29721795Y12816844D01*
X29973141Y12866840D01*
X30229419Y12866840D01*
X30480765Y12816844D01*
X30480765Y12816844D01*
G37*
G36*
X26280765Y12816844D02*
X26280767Y12816843D01*
X26280768Y12816843D01*
X26517535Y12718771D01*
X26730622Y12576391D01*
X26911831Y12395182D01*
X27054211Y12182095D01*
X27152284Y11945325D01*
X27202280Y11693979D01*
X27202280Y11437701D01*
X27152284Y11186355D01*
X27054211Y10949585D01*
X26911831Y10736498D01*
X26730622Y10555289D01*
X26730619Y10555287D01*
X26517535Y10412909D01*
X26280768Y10314837D01*
X26280767Y10314837D01*
X26280765Y10314836D01*
X26029419Y10264840D01*
X25773141Y10264840D01*
X25521795Y10314836D01*
X25521793Y10314837D01*
X25521792Y10314837D01*
X25285025Y10412909D01*
X25071941Y10555287D01*
X25071938Y10555289D01*
X24890729Y10736498D01*
X24748349Y10949585D01*
X24650276Y11186355D01*
X24600280Y11437701D01*
X24600280Y11693979D01*
X24650276Y11945325D01*
X24748349Y12182095D01*
X24890729Y12395182D01*
X25071938Y12576391D01*
X25285025Y12718771D01*
X25521792Y12816843D01*
X25521793Y12816843D01*
X25521795Y12816844D01*
X25773141Y12866840D01*
X26029419Y12866840D01*
X26280765Y12816844D01*
X26280765Y12816844D01*
G37*
G36*
X26280765Y17016844D02*
X26280767Y17016843D01*
X26280768Y17016843D01*
X26517535Y16918771D01*
X26730622Y16776391D01*
X26911831Y16595182D01*
X27054211Y16382095D01*
X27152284Y16145325D01*
X27202280Y15893979D01*
X27202280Y15637701D01*
X27152284Y15386355D01*
X27054211Y15149585D01*
X26911831Y14936498D01*
X26730622Y14755289D01*
X26730619Y14755287D01*
X26517535Y14612909D01*
X26280768Y14514837D01*
X26280767Y14514837D01*
X26280765Y14514836D01*
X26029419Y14464840D01*
X25773141Y14464840D01*
X25521795Y14514836D01*
X25521793Y14514837D01*
X25521792Y14514837D01*
X25285025Y14612909D01*
X25071941Y14755287D01*
X25071938Y14755289D01*
X24890729Y14936498D01*
X24748349Y15149585D01*
X24650276Y15386355D01*
X24600280Y15637701D01*
X24600280Y15893979D01*
X24650276Y16145325D01*
X24748349Y16382095D01*
X24890729Y16595182D01*
X25071938Y16776391D01*
X25285025Y16918771D01*
X25521792Y17016843D01*
X25521793Y17016843D01*
X25521795Y17016844D01*
X25773141Y17066840D01*
X26029419Y17066840D01*
X26280765Y17016844D01*
X26280765Y17016844D01*
G37*
G36*
X10480765Y17016844D02*
X10480767Y17016843D01*
X10480768Y17016843D01*
X10717535Y16918771D01*
X10930622Y16776391D01*
X11111831Y16595182D01*
X11254211Y16382095D01*
X11352284Y16145325D01*
X11402280Y15893979D01*
X11402280Y15637701D01*
X11352284Y15386355D01*
X11254211Y15149585D01*
X11111831Y14936498D01*
X10930622Y14755289D01*
X10930619Y14755287D01*
X10717535Y14612909D01*
X10480768Y14514837D01*
X10480767Y14514837D01*
X10480765Y14514836D01*
X10229419Y14464840D01*
X9973141Y14464840D01*
X9721795Y14514836D01*
X9721793Y14514837D01*
X9721792Y14514837D01*
X9485025Y14612909D01*
X9271941Y14755287D01*
X9271938Y14755289D01*
X9090729Y14936498D01*
X8948349Y15149585D01*
X8850276Y15386355D01*
X8800280Y15637701D01*
X8800280Y15893979D01*
X8850276Y16145325D01*
X8948349Y16382095D01*
X9090729Y16595182D01*
X9271938Y16776391D01*
X9485025Y16918771D01*
X9721792Y17016843D01*
X9721793Y17016843D01*
X9721795Y17016844D01*
X9973141Y17066840D01*
X10229419Y17066840D01*
X10480765Y17016844D01*
X10480765Y17016844D01*
G37*
G36*
X6280765Y17016844D02*
X6280767Y17016843D01*
X6280768Y17016843D01*
X6517535Y16918771D01*
X6730622Y16776391D01*
X6911831Y16595182D01*
X7054211Y16382095D01*
X7152284Y16145325D01*
X7202280Y15893979D01*
X7202280Y15637701D01*
X7152284Y15386355D01*
X7054211Y15149585D01*
X6911831Y14936498D01*
X6730622Y14755289D01*
X6730619Y14755287D01*
X6517535Y14612909D01*
X6280768Y14514837D01*
X6280767Y14514837D01*
X6280765Y14514836D01*
X6029419Y14464840D01*
X5773141Y14464840D01*
X5521795Y14514836D01*
X5521793Y14514837D01*
X5521792Y14514837D01*
X5285025Y14612909D01*
X5071941Y14755287D01*
X5071938Y14755289D01*
X4890729Y14936498D01*
X4748349Y15149585D01*
X4650276Y15386355D01*
X4600280Y15637701D01*
X4600280Y15893979D01*
X4650276Y16145325D01*
X4748349Y16382095D01*
X4890729Y16595182D01*
X5071938Y16776391D01*
X5285025Y16918771D01*
X5521792Y17016843D01*
X5521793Y17016843D01*
X5521795Y17016844D01*
X5773141Y17066840D01*
X6029419Y17066840D01*
X6280765Y17016844D01*
X6280765Y17016844D01*
G37*
G36*
X30480765Y17016844D02*
X30480767Y17016843D01*
X30480768Y17016843D01*
X30717535Y16918771D01*
X30930622Y16776391D01*
X31111831Y16595182D01*
X31254211Y16382095D01*
X31352284Y16145325D01*
X31402280Y15893979D01*
X31402280Y15637701D01*
X31352284Y15386355D01*
X31254211Y15149585D01*
X31111831Y14936498D01*
X30930622Y14755289D01*
X30930619Y14755287D01*
X30717535Y14612909D01*
X30480768Y14514837D01*
X30480767Y14514837D01*
X30480765Y14514836D01*
X30229419Y14464840D01*
X29973141Y14464840D01*
X29721795Y14514836D01*
X29721793Y14514837D01*
X29721792Y14514837D01*
X29485025Y14612909D01*
X29271941Y14755287D01*
X29271938Y14755289D01*
X29090729Y14936498D01*
X28948349Y15149585D01*
X28850276Y15386355D01*
X28800280Y15637701D01*
X28800280Y15893979D01*
X28850276Y16145325D01*
X28948349Y16382095D01*
X29090729Y16595182D01*
X29271938Y16776391D01*
X29485025Y16918771D01*
X29721792Y17016843D01*
X29721793Y17016843D01*
X29721795Y17016844D01*
X29973141Y17066840D01*
X30229419Y17066840D01*
X30480765Y17016844D01*
X30480765Y17016844D01*
G37*
G36*
X26280765Y21216844D02*
X26280767Y21216843D01*
X26280768Y21216843D01*
X26517535Y21118771D01*
X26730622Y20976391D01*
X26911831Y20795182D01*
X27054211Y20582095D01*
X27152284Y20345325D01*
X27202280Y20093979D01*
X27202280Y19837701D01*
X27152284Y19586355D01*
X27054211Y19349585D01*
X26911831Y19136498D01*
X26730622Y18955289D01*
X26730619Y18955287D01*
X26517535Y18812909D01*
X26280768Y18714837D01*
X26280767Y18714837D01*
X26280765Y18714836D01*
X26029419Y18664840D01*
X25773141Y18664840D01*
X25521795Y18714836D01*
X25521793Y18714837D01*
X25521792Y18714837D01*
X25285025Y18812909D01*
X25071941Y18955287D01*
X25071938Y18955289D01*
X24890729Y19136498D01*
X24748349Y19349585D01*
X24650276Y19586355D01*
X24600280Y19837701D01*
X24600280Y20093979D01*
X24650276Y20345325D01*
X24748349Y20582095D01*
X24890729Y20795182D01*
X25071938Y20976391D01*
X25285025Y21118771D01*
X25521792Y21216843D01*
X25521793Y21216843D01*
X25521795Y21216844D01*
X25773141Y21266840D01*
X26029419Y21266840D01*
X26280765Y21216844D01*
X26280765Y21216844D01*
G37*
G36*
X6280765Y21216844D02*
X6280767Y21216843D01*
X6280768Y21216843D01*
X6517535Y21118771D01*
X6730622Y20976391D01*
X6911831Y20795182D01*
X7054211Y20582095D01*
X7152284Y20345325D01*
X7202280Y20093979D01*
X7202280Y19837701D01*
X7152284Y19586355D01*
X7054211Y19349585D01*
X6911831Y19136498D01*
X6730622Y18955289D01*
X6730619Y18955287D01*
X6517535Y18812909D01*
X6280768Y18714837D01*
X6280767Y18714837D01*
X6280765Y18714836D01*
X6029419Y18664840D01*
X5773141Y18664840D01*
X5521795Y18714836D01*
X5521793Y18714837D01*
X5521792Y18714837D01*
X5285025Y18812909D01*
X5071941Y18955287D01*
X5071938Y18955289D01*
X4890729Y19136498D01*
X4748349Y19349585D01*
X4650276Y19586355D01*
X4600280Y19837701D01*
X4600280Y20093979D01*
X4650276Y20345325D01*
X4748349Y20582095D01*
X4890729Y20795182D01*
X5071938Y20976391D01*
X5285025Y21118771D01*
X5521792Y21216843D01*
X5521793Y21216843D01*
X5521795Y21216844D01*
X5773141Y21266840D01*
X6029419Y21266840D01*
X6280765Y21216844D01*
X6280765Y21216844D01*
G37*
G36*
X10480765Y21216844D02*
X10480767Y21216843D01*
X10480768Y21216843D01*
X10717535Y21118771D01*
X10930622Y20976391D01*
X11111831Y20795182D01*
X11254211Y20582095D01*
X11352284Y20345325D01*
X11402280Y20093979D01*
X11402280Y19837701D01*
X11352284Y19586355D01*
X11254211Y19349585D01*
X11111831Y19136498D01*
X10930622Y18955289D01*
X10930619Y18955287D01*
X10717535Y18812909D01*
X10480768Y18714837D01*
X10480767Y18714837D01*
X10480765Y18714836D01*
X10229419Y18664840D01*
X9973141Y18664840D01*
X9721795Y18714836D01*
X9721793Y18714837D01*
X9721792Y18714837D01*
X9485025Y18812909D01*
X9271941Y18955287D01*
X9271938Y18955289D01*
X9090729Y19136498D01*
X8948349Y19349585D01*
X8850276Y19586355D01*
X8800280Y19837701D01*
X8800280Y20093979D01*
X8850276Y20345325D01*
X8948349Y20582095D01*
X9090729Y20795182D01*
X9271938Y20976391D01*
X9485025Y21118771D01*
X9721792Y21216843D01*
X9721793Y21216843D01*
X9721795Y21216844D01*
X9973141Y21266840D01*
X10229419Y21266840D01*
X10480765Y21216844D01*
X10480765Y21216844D01*
G37*
G36*
X30480765Y21216844D02*
X30480767Y21216843D01*
X30480768Y21216843D01*
X30717535Y21118771D01*
X30930622Y20976391D01*
X31111831Y20795182D01*
X31254211Y20582095D01*
X31352284Y20345325D01*
X31402280Y20093979D01*
X31402280Y19837701D01*
X31352284Y19586355D01*
X31254211Y19349585D01*
X31111831Y19136498D01*
X30930622Y18955289D01*
X30930619Y18955287D01*
X30717535Y18812909D01*
X30480768Y18714837D01*
X30480767Y18714837D01*
X30480765Y18714836D01*
X30229419Y18664840D01*
X29973141Y18664840D01*
X29721795Y18714836D01*
X29721793Y18714837D01*
X29721792Y18714837D01*
X29485025Y18812909D01*
X29271941Y18955287D01*
X29271938Y18955289D01*
X29090729Y19136498D01*
X28948349Y19349585D01*
X28850276Y19586355D01*
X28800280Y19837701D01*
X28800280Y20093979D01*
X28850276Y20345325D01*
X28948349Y20582095D01*
X29090729Y20795182D01*
X29271938Y20976391D01*
X29485025Y21118771D01*
X29721792Y21216843D01*
X29721793Y21216843D01*
X29721795Y21216844D01*
X29973141Y21266840D01*
X30229419Y21266840D01*
X30480765Y21216844D01*
X30480765Y21216844D01*
G37*
G36*
X30699532Y26638022D02*
X30699534Y26638021D01*
X30699535Y26638021D01*
X31072793Y26483413D01*
X31072794Y26483412D01*
X31408719Y26258954D01*
X31694394Y25973279D01*
X31694396Y25973276D01*
X31918853Y25637353D01*
X32073461Y25264095D01*
X32152280Y24867846D01*
X32152280Y24463834D01*
X32073461Y24067585D01*
X31918853Y23694327D01*
X31918852Y23694326D01*
X31694394Y23358401D01*
X31408719Y23072726D01*
X31408716Y23072724D01*
X31072793Y22848267D01*
X30699535Y22693659D01*
X30699534Y22693659D01*
X30699532Y22693658D01*
X30303287Y22614840D01*
X29899273Y22614840D01*
X29503028Y22693658D01*
X29503026Y22693659D01*
X29503025Y22693659D01*
X29129767Y22848267D01*
X28793844Y23072724D01*
X28793841Y23072726D01*
X28508166Y23358401D01*
X28283708Y23694326D01*
X28283707Y23694327D01*
X28129099Y24067585D01*
X28050280Y24463834D01*
X28050280Y24867846D01*
X28129099Y25264095D01*
X28283707Y25637353D01*
X28508164Y25973276D01*
X28508166Y25973279D01*
X28793841Y26258954D01*
X29129766Y26483412D01*
X29129767Y26483413D01*
X29503025Y26638021D01*
X29503026Y26638021D01*
X29503028Y26638022D01*
X29899273Y26716840D01*
X30303287Y26716840D01*
X30699532Y26638022D01*
X30699532Y26638022D01*
G37*
G36*
X6499532Y26638022D02*
X6499534Y26638021D01*
X6499535Y26638021D01*
X6872793Y26483413D01*
X6872794Y26483412D01*
X7208719Y26258954D01*
X7494394Y25973279D01*
X7494396Y25973276D01*
X7718853Y25637353D01*
X7873461Y25264095D01*
X7952280Y24867846D01*
X7952280Y24463834D01*
X7873461Y24067585D01*
X7718853Y23694327D01*
X7718852Y23694326D01*
X7494394Y23358401D01*
X7208719Y23072726D01*
X7208716Y23072724D01*
X6872793Y22848267D01*
X6499535Y22693659D01*
X6499534Y22693659D01*
X6499532Y22693658D01*
X6103287Y22614840D01*
X5699273Y22614840D01*
X5303028Y22693658D01*
X5303026Y22693659D01*
X5303025Y22693659D01*
X4929767Y22848267D01*
X4593844Y23072724D01*
X4593841Y23072726D01*
X4308166Y23358401D01*
X4083708Y23694326D01*
X4083707Y23694327D01*
X3929099Y24067585D01*
X3850280Y24463834D01*
X3850280Y24867846D01*
X3929099Y25264095D01*
X4083707Y25637353D01*
X4308164Y25973276D01*
X4308166Y25973279D01*
X4593841Y26258954D01*
X4929766Y26483412D01*
X4929767Y26483413D01*
X5303025Y26638021D01*
X5303026Y26638021D01*
X5303028Y26638022D01*
X5699273Y26716840D01*
X6103287Y26716840D01*
X6499532Y26638022D01*
X6499532Y26638022D01*
G37*
G36*
X57203825Y40259260D02*
X58578018Y39690050D01*
X58578020Y39690049D01*
X59390097Y39147437D01*
X59814765Y38863683D01*
X60866523Y37811925D01*
X60866525Y37811922D01*
X61629564Y36669953D01*
X61692890Y36575178D01*
X62262100Y35200985D01*
X62552280Y33742150D01*
X62552280Y32254730D01*
X62262100Y30795895D01*
X61692890Y29421702D01*
X61692889Y29421700D01*
X61449091Y29056830D01*
X60866523Y28184955D01*
X59814765Y27133197D01*
X59814762Y27133195D01*
X58578020Y26306831D01*
X58578019Y26306830D01*
X58578018Y26306830D01*
X57203825Y25737620D01*
X55744990Y25447440D01*
X54257570Y25447440D01*
X52798735Y25737620D01*
X51424542Y26306830D01*
X51424541Y26306830D01*
X51424540Y26306831D01*
X50187798Y27133195D01*
X50187795Y27133197D01*
X49136037Y28184955D01*
X48553469Y29056830D01*
X48309671Y29421700D01*
X48309670Y29421702D01*
X47740460Y30795895D01*
X47450280Y32254730D01*
X47450280Y33742150D01*
X47740460Y35200985D01*
X48309670Y36575178D01*
X48372997Y36669953D01*
X49136035Y37811922D01*
X49136037Y37811925D01*
X50187795Y38863683D01*
X50612463Y39147437D01*
X51424540Y39690049D01*
X51424542Y39690050D01*
X52798735Y40259260D01*
X54257570Y40549440D01*
X55744990Y40549440D01*
X57203825Y40259260D01*
X57203825Y40259260D01*
G37*
G36*
X117203825Y43009260D02*
X118578018Y42440050D01*
X118578020Y42440049D01*
X119686420Y41699440D01*
X119814765Y41613683D01*
X120866523Y40561925D01*
X120866525Y40561922D01*
X121650990Y39387887D01*
X121692890Y39325178D01*
X122262100Y37950985D01*
X122552280Y36492150D01*
X122552280Y35004730D01*
X122262100Y33545895D01*
X121692890Y32171702D01*
X120866523Y30934955D01*
X119814765Y29883197D01*
X119814762Y29883195D01*
X118578020Y29056831D01*
X118578019Y29056830D01*
X118578018Y29056830D01*
X117203825Y28487620D01*
X115744990Y28197440D01*
X114257570Y28197440D01*
X112798735Y28487620D01*
X111424542Y29056830D01*
X111424541Y29056830D01*
X111424540Y29056831D01*
X110187798Y29883195D01*
X110187795Y29883197D01*
X109136037Y30934955D01*
X108309670Y32171702D01*
X107740460Y33545895D01*
X107450280Y35004730D01*
X107450280Y36492150D01*
X107740460Y37950985D01*
X108309670Y39325178D01*
X108351571Y39387887D01*
X109136035Y40561922D01*
X109136037Y40561925D01*
X110187795Y41613683D01*
X110316140Y41699440D01*
X111424540Y42440049D01*
X111424542Y42440050D01*
X112798735Y43009260D01*
X114257570Y43299440D01*
X115744990Y43299440D01*
X117203825Y43009260D01*
X117203825Y43009260D01*
G37*
G36*
X30699532Y37670622D02*
X30699534Y37670621D01*
X30699535Y37670621D01*
X31072793Y37516013D01*
X31072794Y37516012D01*
X31408719Y37291554D01*
X31694394Y37005879D01*
X31694396Y37005876D01*
X31918853Y36669953D01*
X32073461Y36296695D01*
X32073462Y36296692D01*
X32152280Y35900447D01*
X32152280Y35496433D01*
X32093512Y35200985D01*
X32073461Y35100185D01*
X31918853Y34726927D01*
X31918852Y34726926D01*
X31694394Y34391001D01*
X31408719Y34105326D01*
X31408716Y34105324D01*
X31072793Y33880867D01*
X30699535Y33726259D01*
X30699534Y33726259D01*
X30699532Y33726258D01*
X30303287Y33647440D01*
X29899273Y33647440D01*
X29503028Y33726258D01*
X29503026Y33726259D01*
X29503025Y33726259D01*
X29129767Y33880867D01*
X28793844Y34105324D01*
X28793841Y34105326D01*
X28508166Y34391001D01*
X28283708Y34726926D01*
X28283707Y34726927D01*
X28129099Y35100185D01*
X28109049Y35200985D01*
X28050280Y35496433D01*
X28050280Y35900447D01*
X28129098Y36296692D01*
X28129099Y36296695D01*
X28283707Y36669953D01*
X28508164Y37005876D01*
X28508166Y37005879D01*
X28793841Y37291554D01*
X29129766Y37516012D01*
X29129767Y37516013D01*
X29503025Y37670621D01*
X29503026Y37670621D01*
X29503028Y37670622D01*
X29899273Y37749440D01*
X30303287Y37749440D01*
X30699532Y37670622D01*
X30699532Y37670622D01*
G37*
G36*
X6499532Y37670622D02*
X6499534Y37670621D01*
X6499535Y37670621D01*
X6872793Y37516013D01*
X6872794Y37516012D01*
X7208719Y37291554D01*
X7494394Y37005879D01*
X7494396Y37005876D01*
X7718853Y36669953D01*
X7873461Y36296695D01*
X7873462Y36296692D01*
X7952280Y35900447D01*
X7952280Y35496433D01*
X7893512Y35200985D01*
X7873461Y35100185D01*
X7718853Y34726927D01*
X7718852Y34726926D01*
X7494394Y34391001D01*
X7208719Y34105326D01*
X7208716Y34105324D01*
X6872793Y33880867D01*
X6499535Y33726259D01*
X6499534Y33726259D01*
X6499532Y33726258D01*
X6103287Y33647440D01*
X5699273Y33647440D01*
X5303028Y33726258D01*
X5303026Y33726259D01*
X5303025Y33726259D01*
X4929767Y33880867D01*
X4593844Y34105324D01*
X4593841Y34105326D01*
X4308166Y34391001D01*
X4083708Y34726926D01*
X4083707Y34726927D01*
X3929099Y35100185D01*
X3909049Y35200985D01*
X3850280Y35496433D01*
X3850280Y35900447D01*
X3929098Y36296692D01*
X3929099Y36296695D01*
X4083707Y36669953D01*
X4308164Y37005876D01*
X4308166Y37005879D01*
X4593841Y37291554D01*
X4929766Y37516012D01*
X4929767Y37516013D01*
X5303025Y37670621D01*
X5303026Y37670621D01*
X5303028Y37670622D01*
X5699273Y37749440D01*
X6103287Y37749440D01*
X6499532Y37670622D01*
X6499532Y37670622D01*
G37*
G36*
X10480765Y41649444D02*
X10480767Y41649443D01*
X10480768Y41649443D01*
X10567100Y41613683D01*
X10717535Y41551371D01*
X10930622Y41408991D01*
X11111831Y41227782D01*
X11254211Y41014695D01*
X11352284Y40777925D01*
X11402280Y40526579D01*
X11402280Y40270301D01*
X11352284Y40018955D01*
X11254211Y39782185D01*
X11111831Y39569098D01*
X10930622Y39387889D01*
X10930619Y39387887D01*
X10717535Y39245509D01*
X10480768Y39147437D01*
X10480767Y39147437D01*
X10480765Y39147436D01*
X10229419Y39097440D01*
X9973141Y39097440D01*
X9721795Y39147436D01*
X9721793Y39147437D01*
X9721792Y39147437D01*
X9485025Y39245509D01*
X9271941Y39387887D01*
X9271938Y39387889D01*
X9090729Y39569098D01*
X8948349Y39782185D01*
X8850276Y40018955D01*
X8800280Y40270301D01*
X8800280Y40526579D01*
X8850276Y40777925D01*
X8948349Y41014695D01*
X9090729Y41227782D01*
X9271938Y41408991D01*
X9485025Y41551371D01*
X9635460Y41613683D01*
X9721792Y41649443D01*
X9721793Y41649443D01*
X9721795Y41649444D01*
X9973141Y41699440D01*
X10229419Y41699440D01*
X10480765Y41649444D01*
X10480765Y41649444D01*
G37*
G36*
X6280765Y41649444D02*
X6280767Y41649443D01*
X6280768Y41649443D01*
X6367100Y41613683D01*
X6517535Y41551371D01*
X6730622Y41408991D01*
X6911831Y41227782D01*
X7054211Y41014695D01*
X7152284Y40777925D01*
X7202280Y40526579D01*
X7202280Y40270301D01*
X7152284Y40018955D01*
X7054211Y39782185D01*
X6911831Y39569098D01*
X6730622Y39387889D01*
X6730619Y39387887D01*
X6517535Y39245509D01*
X6280768Y39147437D01*
X6280767Y39147437D01*
X6280765Y39147436D01*
X6029419Y39097440D01*
X5773141Y39097440D01*
X5521795Y39147436D01*
X5521793Y39147437D01*
X5521792Y39147437D01*
X5285025Y39245509D01*
X5071941Y39387887D01*
X5071938Y39387889D01*
X4890729Y39569098D01*
X4748349Y39782185D01*
X4650276Y40018955D01*
X4600280Y40270301D01*
X4600280Y40526579D01*
X4650276Y40777925D01*
X4748349Y41014695D01*
X4890729Y41227782D01*
X5071938Y41408991D01*
X5285025Y41551371D01*
X5435460Y41613683D01*
X5521792Y41649443D01*
X5521793Y41649443D01*
X5521795Y41649444D01*
X5773141Y41699440D01*
X6029419Y41699440D01*
X6280765Y41649444D01*
X6280765Y41649444D01*
G37*
G36*
X30480765Y41649444D02*
X30480767Y41649443D01*
X30480768Y41649443D01*
X30567100Y41613683D01*
X30717535Y41551371D01*
X30930622Y41408991D01*
X31111831Y41227782D01*
X31254211Y41014695D01*
X31352284Y40777925D01*
X31402280Y40526579D01*
X31402280Y40270301D01*
X31352284Y40018955D01*
X31254211Y39782185D01*
X31111831Y39569098D01*
X30930622Y39387889D01*
X30930619Y39387887D01*
X30717535Y39245509D01*
X30480768Y39147437D01*
X30480767Y39147437D01*
X30480765Y39147436D01*
X30229419Y39097440D01*
X29973141Y39097440D01*
X29721795Y39147436D01*
X29721793Y39147437D01*
X29721792Y39147437D01*
X29485025Y39245509D01*
X29271941Y39387887D01*
X29271938Y39387889D01*
X29090729Y39569098D01*
X28948349Y39782185D01*
X28850276Y40018955D01*
X28800280Y40270301D01*
X28800280Y40526579D01*
X28850276Y40777925D01*
X28948349Y41014695D01*
X29090729Y41227782D01*
X29271938Y41408991D01*
X29485025Y41551371D01*
X29635460Y41613683D01*
X29721792Y41649443D01*
X29721793Y41649443D01*
X29721795Y41649444D01*
X29973141Y41699440D01*
X30229419Y41699440D01*
X30480765Y41649444D01*
X30480765Y41649444D01*
G37*
G36*
X26280765Y41649444D02*
X26280767Y41649443D01*
X26280768Y41649443D01*
X26367100Y41613683D01*
X26517535Y41551371D01*
X26730622Y41408991D01*
X26911831Y41227782D01*
X27054211Y41014695D01*
X27152284Y40777925D01*
X27202280Y40526579D01*
X27202280Y40270301D01*
X27152284Y40018955D01*
X27054211Y39782185D01*
X26911831Y39569098D01*
X26730622Y39387889D01*
X26730619Y39387887D01*
X26517535Y39245509D01*
X26280768Y39147437D01*
X26280767Y39147437D01*
X26280765Y39147436D01*
X26029419Y39097440D01*
X25773141Y39097440D01*
X25521795Y39147436D01*
X25521793Y39147437D01*
X25521792Y39147437D01*
X25285025Y39245509D01*
X25071941Y39387887D01*
X25071938Y39387889D01*
X24890729Y39569098D01*
X24748349Y39782185D01*
X24650276Y40018955D01*
X24600280Y40270301D01*
X24600280Y40526579D01*
X24650276Y40777925D01*
X24748349Y41014695D01*
X24890729Y41227782D01*
X25071938Y41408991D01*
X25285025Y41551371D01*
X25435460Y41613683D01*
X25521792Y41649443D01*
X25521793Y41649443D01*
X25521795Y41649444D01*
X25773141Y41699440D01*
X26029419Y41699440D01*
X26280765Y41649444D01*
X26280765Y41649444D01*
G37*
G36*
X30480765Y45849444D02*
X30480767Y45849443D01*
X30480768Y45849443D01*
X30717535Y45751371D01*
X30930622Y45608991D01*
X31111831Y45427782D01*
X31254211Y45214695D01*
X31352284Y44977925D01*
X31402280Y44726579D01*
X31402280Y44470301D01*
X31352284Y44218955D01*
X31254211Y43982185D01*
X31111831Y43769098D01*
X30930622Y43587889D01*
X30930619Y43587887D01*
X30717535Y43445509D01*
X30480768Y43347437D01*
X30480767Y43347437D01*
X30480765Y43347436D01*
X30229419Y43297440D01*
X29973141Y43297440D01*
X29721795Y43347436D01*
X29721793Y43347437D01*
X29721792Y43347437D01*
X29485025Y43445509D01*
X29271941Y43587887D01*
X29271938Y43587889D01*
X29090729Y43769098D01*
X28948349Y43982185D01*
X28850276Y44218955D01*
X28800280Y44470301D01*
X28800280Y44726579D01*
X28850276Y44977925D01*
X28948349Y45214695D01*
X29090729Y45427782D01*
X29271938Y45608991D01*
X29485025Y45751371D01*
X29721792Y45849443D01*
X29721793Y45849443D01*
X29721795Y45849444D01*
X29973141Y45899440D01*
X30229419Y45899440D01*
X30480765Y45849444D01*
X30480765Y45849444D01*
G37*
G36*
X6280765Y45849444D02*
X6280767Y45849443D01*
X6280768Y45849443D01*
X6517535Y45751371D01*
X6730622Y45608991D01*
X6911831Y45427782D01*
X7054211Y45214695D01*
X7152284Y44977925D01*
X7202280Y44726579D01*
X7202280Y44470301D01*
X7152284Y44218955D01*
X7054211Y43982185D01*
X6911831Y43769098D01*
X6730622Y43587889D01*
X6730619Y43587887D01*
X6517535Y43445509D01*
X6280768Y43347437D01*
X6280767Y43347437D01*
X6280765Y43347436D01*
X6029419Y43297440D01*
X5773141Y43297440D01*
X5521795Y43347436D01*
X5521793Y43347437D01*
X5521792Y43347437D01*
X5285025Y43445509D01*
X5071941Y43587887D01*
X5071938Y43587889D01*
X4890729Y43769098D01*
X4748349Y43982185D01*
X4650276Y44218955D01*
X4600280Y44470301D01*
X4600280Y44726579D01*
X4650276Y44977925D01*
X4748349Y45214695D01*
X4890729Y45427782D01*
X5071938Y45608991D01*
X5285025Y45751371D01*
X5521792Y45849443D01*
X5521793Y45849443D01*
X5521795Y45849444D01*
X5773141Y45899440D01*
X6029419Y45899440D01*
X6280765Y45849444D01*
X6280765Y45849444D01*
G37*
G36*
X26280765Y45849444D02*
X26280767Y45849443D01*
X26280768Y45849443D01*
X26517535Y45751371D01*
X26730622Y45608991D01*
X26911831Y45427782D01*
X27054211Y45214695D01*
X27152284Y44977925D01*
X27202280Y44726579D01*
X27202280Y44470301D01*
X27152284Y44218955D01*
X27054211Y43982185D01*
X26911831Y43769098D01*
X26730622Y43587889D01*
X26730619Y43587887D01*
X26517535Y43445509D01*
X26280768Y43347437D01*
X26280767Y43347437D01*
X26280765Y43347436D01*
X26029419Y43297440D01*
X25773141Y43297440D01*
X25521795Y43347436D01*
X25521793Y43347437D01*
X25521792Y43347437D01*
X25285025Y43445509D01*
X25071941Y43587887D01*
X25071938Y43587889D01*
X24890729Y43769098D01*
X24748349Y43982185D01*
X24650276Y44218955D01*
X24600280Y44470301D01*
X24600280Y44726579D01*
X24650276Y44977925D01*
X24748349Y45214695D01*
X24890729Y45427782D01*
X25071938Y45608991D01*
X25285025Y45751371D01*
X25521792Y45849443D01*
X25521793Y45849443D01*
X25521795Y45849444D01*
X25773141Y45899440D01*
X26029419Y45899440D01*
X26280765Y45849444D01*
X26280765Y45849444D01*
G37*
G36*
X10480765Y45849444D02*
X10480767Y45849443D01*
X10480768Y45849443D01*
X10717535Y45751371D01*
X10930622Y45608991D01*
X11111831Y45427782D01*
X11254211Y45214695D01*
X11352284Y44977925D01*
X11402280Y44726579D01*
X11402280Y44470301D01*
X11352284Y44218955D01*
X11254211Y43982185D01*
X11111831Y43769098D01*
X10930622Y43587889D01*
X10930619Y43587887D01*
X10717535Y43445509D01*
X10480768Y43347437D01*
X10480767Y43347437D01*
X10480765Y43347436D01*
X10229419Y43297440D01*
X9973141Y43297440D01*
X9721795Y43347436D01*
X9721793Y43347437D01*
X9721792Y43347437D01*
X9485025Y43445509D01*
X9271941Y43587887D01*
X9271938Y43587889D01*
X9090729Y43769098D01*
X8948349Y43982185D01*
X8850276Y44218955D01*
X8800280Y44470301D01*
X8800280Y44726579D01*
X8850276Y44977925D01*
X8948349Y45214695D01*
X9090729Y45427782D01*
X9271938Y45608991D01*
X9485025Y45751371D01*
X9721792Y45849443D01*
X9721793Y45849443D01*
X9721795Y45849444D01*
X9973141Y45899440D01*
X10229419Y45899440D01*
X10480765Y45849444D01*
X10480765Y45849444D01*
G37*
G36*
X30480765Y50049444D02*
X30480767Y50049443D01*
X30480768Y50049443D01*
X30717535Y49951371D01*
X30930622Y49808991D01*
X31111831Y49627782D01*
X31254211Y49414695D01*
X31352284Y49177925D01*
X31402280Y48926579D01*
X31402280Y48670301D01*
X31352284Y48418955D01*
X31254211Y48182185D01*
X31111831Y47969098D01*
X30930622Y47787889D01*
X30930619Y47787887D01*
X30717535Y47645509D01*
X30480768Y47547437D01*
X30480767Y47547437D01*
X30480765Y47547436D01*
X30229419Y47497440D01*
X29973141Y47497440D01*
X29721795Y47547436D01*
X29721793Y47547437D01*
X29721792Y47547437D01*
X29485025Y47645509D01*
X29271941Y47787887D01*
X29271938Y47787889D01*
X29090729Y47969098D01*
X28948349Y48182185D01*
X28850276Y48418955D01*
X28800280Y48670301D01*
X28800280Y48926579D01*
X28850276Y49177925D01*
X28948349Y49414695D01*
X29090729Y49627782D01*
X29271938Y49808991D01*
X29485025Y49951371D01*
X29721792Y50049443D01*
X29721793Y50049443D01*
X29721795Y50049444D01*
X29973141Y50099440D01*
X30229419Y50099440D01*
X30480765Y50049444D01*
X30480765Y50049444D01*
G37*
G36*
X6280765Y50049444D02*
X6280767Y50049443D01*
X6280768Y50049443D01*
X6517535Y49951371D01*
X6730622Y49808991D01*
X6911831Y49627782D01*
X7054211Y49414695D01*
X7152284Y49177925D01*
X7202280Y48926579D01*
X7202280Y48670301D01*
X7152284Y48418955D01*
X7054211Y48182185D01*
X6911831Y47969098D01*
X6730622Y47787889D01*
X6730619Y47787887D01*
X6517535Y47645509D01*
X6280768Y47547437D01*
X6280767Y47547437D01*
X6280765Y47547436D01*
X6029419Y47497440D01*
X5773141Y47497440D01*
X5521795Y47547436D01*
X5521793Y47547437D01*
X5521792Y47547437D01*
X5285025Y47645509D01*
X5071941Y47787887D01*
X5071938Y47787889D01*
X4890729Y47969098D01*
X4748349Y48182185D01*
X4650276Y48418955D01*
X4600280Y48670301D01*
X4600280Y48926579D01*
X4650276Y49177925D01*
X4748349Y49414695D01*
X4890729Y49627782D01*
X5071938Y49808991D01*
X5285025Y49951371D01*
X5521792Y50049443D01*
X5521793Y50049443D01*
X5521795Y50049444D01*
X5773141Y50099440D01*
X6029419Y50099440D01*
X6280765Y50049444D01*
X6280765Y50049444D01*
G37*
G36*
X10480765Y50049444D02*
X10480767Y50049443D01*
X10480768Y50049443D01*
X10717535Y49951371D01*
X10930622Y49808991D01*
X11111831Y49627782D01*
X11254211Y49414695D01*
X11352284Y49177925D01*
X11402280Y48926579D01*
X11402280Y48670301D01*
X11352284Y48418955D01*
X11254211Y48182185D01*
X11111831Y47969098D01*
X10930622Y47787889D01*
X10930619Y47787887D01*
X10717535Y47645509D01*
X10480768Y47547437D01*
X10480767Y47547437D01*
X10480765Y47547436D01*
X10229419Y47497440D01*
X9973141Y47497440D01*
X9721795Y47547436D01*
X9721793Y47547437D01*
X9721792Y47547437D01*
X9485025Y47645509D01*
X9271941Y47787887D01*
X9271938Y47787889D01*
X9090729Y47969098D01*
X8948349Y48182185D01*
X8850276Y48418955D01*
X8800280Y48670301D01*
X8800280Y48926579D01*
X8850276Y49177925D01*
X8948349Y49414695D01*
X9090729Y49627782D01*
X9271938Y49808991D01*
X9485025Y49951371D01*
X9721792Y50049443D01*
X9721793Y50049443D01*
X9721795Y50049444D01*
X9973141Y50099440D01*
X10229419Y50099440D01*
X10480765Y50049444D01*
X10480765Y50049444D01*
G37*
G36*
X26280765Y50049444D02*
X26280767Y50049443D01*
X26280768Y50049443D01*
X26517535Y49951371D01*
X26730622Y49808991D01*
X26911831Y49627782D01*
X27054211Y49414695D01*
X27152284Y49177925D01*
X27202280Y48926579D01*
X27202280Y48670301D01*
X27152284Y48418955D01*
X27054211Y48182185D01*
X26911831Y47969098D01*
X26730622Y47787889D01*
X26730619Y47787887D01*
X26517535Y47645509D01*
X26280768Y47547437D01*
X26280767Y47547437D01*
X26280765Y47547436D01*
X26029419Y47497440D01*
X25773141Y47497440D01*
X25521795Y47547436D01*
X25521793Y47547437D01*
X25521792Y47547437D01*
X25285025Y47645509D01*
X25071941Y47787887D01*
X25071938Y47787889D01*
X24890729Y47969098D01*
X24748349Y48182185D01*
X24650276Y48418955D01*
X24600280Y48670301D01*
X24600280Y48926579D01*
X24650276Y49177925D01*
X24748349Y49414695D01*
X24890729Y49627782D01*
X25071938Y49808991D01*
X25285025Y49951371D01*
X25521792Y50049443D01*
X25521793Y50049443D01*
X25521795Y50049444D01*
X25773141Y50099440D01*
X26029419Y50099440D01*
X26280765Y50049444D01*
X26280765Y50049444D01*
G37*
G36*
X57203825Y62759260D02*
X58578018Y62190050D01*
X58578020Y62190049D01*
X59011440Y61900447D01*
X59814765Y61363683D01*
X60866523Y60311925D01*
X60866525Y60311922D01*
X61154547Y59880867D01*
X61692890Y59075178D01*
X62262100Y57700985D01*
X62552280Y56242150D01*
X62552280Y54754730D01*
X62262100Y53295895D01*
X61804437Y52191001D01*
X61692889Y51921700D01*
X61449091Y51556830D01*
X60866523Y50684955D01*
X59814765Y49633197D01*
X59814762Y49633195D01*
X58578020Y48806831D01*
X58578019Y48806830D01*
X58578018Y48806830D01*
X57203825Y48237620D01*
X55744990Y47947440D01*
X54257570Y47947440D01*
X52798735Y48237620D01*
X51424542Y48806830D01*
X51424541Y48806830D01*
X51424540Y48806831D01*
X50187798Y49633195D01*
X50187795Y49633197D01*
X49136037Y50684955D01*
X48553469Y51556830D01*
X48309671Y51921700D01*
X48198123Y52191001D01*
X47740460Y53295895D01*
X47450280Y54754730D01*
X47450280Y56242150D01*
X47740460Y57700985D01*
X48309670Y59075178D01*
X48848014Y59880867D01*
X49136035Y60311922D01*
X49136037Y60311925D01*
X50187795Y61363683D01*
X50991120Y61900447D01*
X51424540Y62190049D01*
X51424542Y62190050D01*
X52798735Y62759260D01*
X54257570Y63049440D01*
X55744990Y63049440D01*
X57203825Y62759260D01*
X57203825Y62759260D01*
G37*
G36*
X117203825Y65509260D02*
X118578018Y64940050D01*
X118578020Y64940049D01*
X119798314Y64124675D01*
X119814765Y64113683D01*
X120866523Y63061925D01*
X120866525Y63061922D01*
X121449092Y62190049D01*
X121692890Y61825178D01*
X122262100Y60450985D01*
X122552280Y58992150D01*
X122552280Y57504730D01*
X122262100Y56045895D01*
X121727282Y54754731D01*
X121692889Y54671700D01*
X121558086Y54469953D01*
X120866523Y53434955D01*
X119814765Y52383197D01*
X119814762Y52383195D01*
X118578020Y51556831D01*
X118578019Y51556830D01*
X118578018Y51556830D01*
X117203825Y50987620D01*
X115744990Y50697440D01*
X114257570Y50697440D01*
X112798735Y50987620D01*
X111424542Y51556830D01*
X111424541Y51556830D01*
X111424540Y51556831D01*
X110187798Y52383195D01*
X110187795Y52383197D01*
X109136037Y53434955D01*
X108444474Y54469953D01*
X108309671Y54671700D01*
X108275278Y54754731D01*
X107740460Y56045895D01*
X107450280Y57504730D01*
X107450280Y58992150D01*
X107740460Y60450985D01*
X108309670Y61825178D01*
X108553469Y62190049D01*
X109136035Y63061922D01*
X109136037Y63061925D01*
X110187795Y64113683D01*
X110204246Y64124675D01*
X111424540Y64940049D01*
X111424542Y64940050D01*
X112798735Y65509260D01*
X114257570Y65799440D01*
X115744990Y65799440D01*
X117203825Y65509260D01*
X117203825Y65509260D01*
G37*
G36*
X6499532Y55470622D02*
X6499534Y55470621D01*
X6499535Y55470621D01*
X6872793Y55316013D01*
X6872794Y55316012D01*
X7208719Y55091554D01*
X7494394Y54805879D01*
X7494396Y54805876D01*
X7718853Y54469953D01*
X7873461Y54096695D01*
X7952280Y53700446D01*
X7952280Y53296434D01*
X7873461Y52900185D01*
X7718853Y52526927D01*
X7622814Y52383195D01*
X7494394Y52191001D01*
X7208719Y51905326D01*
X7208716Y51905324D01*
X6872793Y51680867D01*
X6499535Y51526259D01*
X6499534Y51526259D01*
X6499532Y51526258D01*
X6103287Y51447440D01*
X5699273Y51447440D01*
X5303028Y51526258D01*
X5303026Y51526259D01*
X5303025Y51526259D01*
X4929767Y51680867D01*
X4593844Y51905324D01*
X4593841Y51905326D01*
X4308166Y52191001D01*
X4179746Y52383195D01*
X4083707Y52526927D01*
X3929099Y52900185D01*
X3850280Y53296434D01*
X3850280Y53700446D01*
X3929099Y54096695D01*
X4083707Y54469953D01*
X4308164Y54805876D01*
X4308166Y54805879D01*
X4593841Y55091554D01*
X4929766Y55316012D01*
X4929767Y55316013D01*
X5303025Y55470621D01*
X5303026Y55470621D01*
X5303028Y55470622D01*
X5699273Y55549440D01*
X6103287Y55549440D01*
X6499532Y55470622D01*
X6499532Y55470622D01*
G37*
G36*
X30699532Y55470622D02*
X30699534Y55470621D01*
X30699535Y55470621D01*
X31072793Y55316013D01*
X31072794Y55316012D01*
X31408719Y55091554D01*
X31694394Y54805879D01*
X31694396Y54805876D01*
X31918853Y54469953D01*
X32073461Y54096695D01*
X32152280Y53700446D01*
X32152280Y53296434D01*
X32073461Y52900185D01*
X31918853Y52526927D01*
X31822814Y52383195D01*
X31694394Y52191001D01*
X31408719Y51905326D01*
X31408716Y51905324D01*
X31072793Y51680867D01*
X30699535Y51526259D01*
X30699534Y51526259D01*
X30699532Y51526258D01*
X30303287Y51447440D01*
X29899273Y51447440D01*
X29503028Y51526258D01*
X29503026Y51526259D01*
X29503025Y51526259D01*
X29129767Y51680867D01*
X28793844Y51905324D01*
X28793841Y51905326D01*
X28508166Y52191001D01*
X28379746Y52383195D01*
X28283707Y52526927D01*
X28129099Y52900185D01*
X28050280Y53296434D01*
X28050280Y53700446D01*
X28129099Y54096695D01*
X28283707Y54469953D01*
X28508164Y54805876D01*
X28508166Y54805879D01*
X28793841Y55091554D01*
X29129766Y55316012D01*
X29129767Y55316013D01*
X29503025Y55470621D01*
X29503026Y55470621D01*
X29503028Y55470622D01*
X29899273Y55549440D01*
X30303287Y55549440D01*
X30699532Y55470622D01*
X30699532Y55470622D01*
G37*
G36*
X30699532Y63670622D02*
X30699534Y63670621D01*
X30699535Y63670621D01*
X31072793Y63516013D01*
X31072794Y63516012D01*
X31408719Y63291554D01*
X31694394Y63005879D01*
X31694396Y63005876D01*
X31918853Y62669953D01*
X32073461Y62296695D01*
X32073462Y62296692D01*
X32152280Y61900447D01*
X32152280Y61496434D01*
X32073461Y61100185D01*
X31918853Y60726927D01*
X31918852Y60726926D01*
X31694394Y60391001D01*
X31408719Y60105326D01*
X31408716Y60105324D01*
X31072793Y59880867D01*
X30699535Y59726259D01*
X30699534Y59726259D01*
X30699532Y59726258D01*
X30303287Y59647440D01*
X29899273Y59647440D01*
X29503028Y59726258D01*
X29503026Y59726259D01*
X29503025Y59726259D01*
X29129767Y59880867D01*
X28793844Y60105324D01*
X28793841Y60105326D01*
X28508166Y60391001D01*
X28283708Y60726926D01*
X28283707Y60726927D01*
X28129099Y61100185D01*
X28050280Y61496434D01*
X28050280Y61900447D01*
X28129098Y62296692D01*
X28129099Y62296695D01*
X28283707Y62669953D01*
X28508164Y63005876D01*
X28508166Y63005879D01*
X28793841Y63291554D01*
X29129766Y63516012D01*
X29129767Y63516013D01*
X29503025Y63670621D01*
X29503026Y63670621D01*
X29503028Y63670622D01*
X29899273Y63749440D01*
X30303287Y63749440D01*
X30699532Y63670622D01*
X30699532Y63670622D01*
G37*
G36*
X6499532Y63670622D02*
X6499534Y63670621D01*
X6499535Y63670621D01*
X6872793Y63516013D01*
X6872794Y63516012D01*
X7208719Y63291554D01*
X7494394Y63005879D01*
X7494396Y63005876D01*
X7718853Y62669953D01*
X7873461Y62296695D01*
X7873462Y62296692D01*
X7952280Y61900447D01*
X7952280Y61496434D01*
X7873461Y61100185D01*
X7718853Y60726927D01*
X7718852Y60726926D01*
X7494394Y60391001D01*
X7208719Y60105326D01*
X7208716Y60105324D01*
X6872793Y59880867D01*
X6499535Y59726259D01*
X6499534Y59726259D01*
X6499532Y59726258D01*
X6103287Y59647440D01*
X5699273Y59647440D01*
X5303028Y59726258D01*
X5303026Y59726259D01*
X5303025Y59726259D01*
X4929767Y59880867D01*
X4593844Y60105324D01*
X4593841Y60105326D01*
X4308166Y60391001D01*
X4083708Y60726926D01*
X4083707Y60726927D01*
X3929099Y61100185D01*
X3850280Y61496434D01*
X3850280Y61900447D01*
X3929098Y62296692D01*
X3929099Y62296695D01*
X4083707Y62669953D01*
X4308164Y63005876D01*
X4308166Y63005879D01*
X4593841Y63291554D01*
X4929766Y63516012D01*
X4929767Y63516013D01*
X5303025Y63670621D01*
X5303026Y63670621D01*
X5303028Y63670622D01*
X5699273Y63749440D01*
X6103287Y63749440D01*
X6499532Y63670622D01*
X6499532Y63670622D01*
G37*
G36*
X10680765Y67649444D02*
X10680767Y67649443D01*
X10680768Y67649443D01*
X10917535Y67551371D01*
X11130622Y67408991D01*
X11311831Y67227782D01*
X11454211Y67014695D01*
X11552284Y66777925D01*
X11602280Y66526579D01*
X11602280Y66270301D01*
X11552284Y66018955D01*
X11454211Y65782185D01*
X11311831Y65569098D01*
X11130622Y65387889D01*
X11130619Y65387887D01*
X10917535Y65245509D01*
X10680768Y65147437D01*
X10680767Y65147437D01*
X10680765Y65147436D01*
X10429419Y65097440D01*
X10173141Y65097440D01*
X9921795Y65147436D01*
X9921793Y65147437D01*
X9921792Y65147437D01*
X9685025Y65245509D01*
X9471941Y65387887D01*
X9471938Y65387889D01*
X9290729Y65569098D01*
X9148349Y65782185D01*
X9050276Y66018955D01*
X9000280Y66270301D01*
X9000280Y66526579D01*
X9050276Y66777925D01*
X9148349Y67014695D01*
X9290729Y67227782D01*
X9471938Y67408991D01*
X9685025Y67551371D01*
X9921792Y67649443D01*
X9921793Y67649443D01*
X9921795Y67649444D01*
X10173141Y67699440D01*
X10429419Y67699440D01*
X10680765Y67649444D01*
X10680765Y67649444D01*
G37*
G36*
X26080765Y67649444D02*
X26080767Y67649443D01*
X26080768Y67649443D01*
X26317535Y67551371D01*
X26530622Y67408991D01*
X26711831Y67227782D01*
X26854211Y67014695D01*
X26952284Y66777925D01*
X27002280Y66526579D01*
X27002280Y66270301D01*
X26952284Y66018955D01*
X26854211Y65782185D01*
X26711831Y65569098D01*
X26530622Y65387889D01*
X26530619Y65387887D01*
X26317535Y65245509D01*
X26080768Y65147437D01*
X26080767Y65147437D01*
X26080765Y65147436D01*
X25829419Y65097440D01*
X25573141Y65097440D01*
X25321795Y65147436D01*
X25321793Y65147437D01*
X25321792Y65147437D01*
X25085025Y65245509D01*
X24871941Y65387887D01*
X24871938Y65387889D01*
X24690729Y65569098D01*
X24548349Y65782185D01*
X24450276Y66018955D01*
X24400280Y66270301D01*
X24400280Y66526579D01*
X24450276Y66777925D01*
X24548349Y67014695D01*
X24690729Y67227782D01*
X24871938Y67408991D01*
X25085025Y67551371D01*
X25321792Y67649443D01*
X25321793Y67649443D01*
X25321795Y67649444D01*
X25573141Y67699440D01*
X25829419Y67699440D01*
X26080765Y67649444D01*
X26080765Y67649444D01*
G37*
G36*
X30280765Y67649444D02*
X30280767Y67649443D01*
X30280768Y67649443D01*
X30517535Y67551371D01*
X30730622Y67408991D01*
X30911831Y67227782D01*
X31054211Y67014695D01*
X31152284Y66777925D01*
X31202280Y66526579D01*
X31202280Y66270301D01*
X31152284Y66018955D01*
X31054211Y65782185D01*
X30911831Y65569098D01*
X30730622Y65387889D01*
X30730619Y65387887D01*
X30517535Y65245509D01*
X30280768Y65147437D01*
X30280767Y65147437D01*
X30280765Y65147436D01*
X30029419Y65097440D01*
X29773141Y65097440D01*
X29521795Y65147436D01*
X29521793Y65147437D01*
X29521792Y65147437D01*
X29285025Y65245509D01*
X29071941Y65387887D01*
X29071938Y65387889D01*
X28890729Y65569098D01*
X28748349Y65782185D01*
X28650276Y66018955D01*
X28600280Y66270301D01*
X28600280Y66526579D01*
X28650276Y66777925D01*
X28748349Y67014695D01*
X28890729Y67227782D01*
X29071938Y67408991D01*
X29285025Y67551371D01*
X29521792Y67649443D01*
X29521793Y67649443D01*
X29521795Y67649444D01*
X29773141Y67699440D01*
X30029419Y67699440D01*
X30280765Y67649444D01*
X30280765Y67649444D01*
G37*
G36*
X6480765Y67649444D02*
X6480767Y67649443D01*
X6480768Y67649443D01*
X6717535Y67551371D01*
X6930622Y67408991D01*
X7111831Y67227782D01*
X7254211Y67014695D01*
X7352284Y66777925D01*
X7402280Y66526579D01*
X7402280Y66270301D01*
X7352284Y66018955D01*
X7254211Y65782185D01*
X7111831Y65569098D01*
X6930622Y65387889D01*
X6930619Y65387887D01*
X6717535Y65245509D01*
X6480768Y65147437D01*
X6480767Y65147437D01*
X6480765Y65147436D01*
X6229419Y65097440D01*
X5973141Y65097440D01*
X5721795Y65147436D01*
X5721793Y65147437D01*
X5721792Y65147437D01*
X5485025Y65245509D01*
X5271941Y65387887D01*
X5271938Y65387889D01*
X5090729Y65569098D01*
X4948349Y65782185D01*
X4850276Y66018955D01*
X4800280Y66270301D01*
X4800280Y66526579D01*
X4850276Y66777925D01*
X4948349Y67014695D01*
X5090729Y67227782D01*
X5271938Y67408991D01*
X5485025Y67551371D01*
X5721792Y67649443D01*
X5721793Y67649443D01*
X5721795Y67649444D01*
X5973141Y67699440D01*
X6229419Y67699440D01*
X6480765Y67649444D01*
X6480765Y67649444D01*
G37*
G36*
X10680765Y71849444D02*
X10680767Y71849443D01*
X10680768Y71849443D01*
X10917535Y71751371D01*
X11130622Y71608991D01*
X11311831Y71427782D01*
X11454211Y71214695D01*
X11552284Y70977925D01*
X11602280Y70726579D01*
X11602280Y70470301D01*
X11552284Y70218955D01*
X11454211Y69982185D01*
X11311831Y69769098D01*
X11130622Y69587889D01*
X11130619Y69587887D01*
X10917535Y69445509D01*
X10680768Y69347437D01*
X10680767Y69347437D01*
X10680765Y69347436D01*
X10429419Y69297440D01*
X10173141Y69297440D01*
X9921795Y69347436D01*
X9921793Y69347437D01*
X9921792Y69347437D01*
X9685025Y69445509D01*
X9471941Y69587887D01*
X9471938Y69587889D01*
X9290729Y69769098D01*
X9148349Y69982185D01*
X9050276Y70218955D01*
X9000280Y70470301D01*
X9000280Y70726579D01*
X9050276Y70977925D01*
X9148349Y71214695D01*
X9290729Y71427782D01*
X9471938Y71608991D01*
X9685025Y71751371D01*
X9921792Y71849443D01*
X9921793Y71849443D01*
X9921795Y71849444D01*
X10173141Y71899440D01*
X10429419Y71899440D01*
X10680765Y71849444D01*
X10680765Y71849444D01*
G37*
G36*
X26080765Y71849444D02*
X26080767Y71849443D01*
X26080768Y71849443D01*
X26317535Y71751371D01*
X26530622Y71608991D01*
X26711831Y71427782D01*
X26854211Y71214695D01*
X26952284Y70977925D01*
X27002280Y70726579D01*
X27002280Y70470301D01*
X26952284Y70218955D01*
X26854211Y69982185D01*
X26711831Y69769098D01*
X26530622Y69587889D01*
X26530619Y69587887D01*
X26317535Y69445509D01*
X26080768Y69347437D01*
X26080767Y69347437D01*
X26080765Y69347436D01*
X25829419Y69297440D01*
X25573141Y69297440D01*
X25321795Y69347436D01*
X25321793Y69347437D01*
X25321792Y69347437D01*
X25085025Y69445509D01*
X24871941Y69587887D01*
X24871938Y69587889D01*
X24690729Y69769098D01*
X24548349Y69982185D01*
X24450276Y70218955D01*
X24400280Y70470301D01*
X24400280Y70726579D01*
X24450276Y70977925D01*
X24548349Y71214695D01*
X24690729Y71427782D01*
X24871938Y71608991D01*
X25085025Y71751371D01*
X25321792Y71849443D01*
X25321793Y71849443D01*
X25321795Y71849444D01*
X25573141Y71899440D01*
X25829419Y71899440D01*
X26080765Y71849444D01*
X26080765Y71849444D01*
G37*
G36*
X30280765Y71849444D02*
X30280767Y71849443D01*
X30280768Y71849443D01*
X30517535Y71751371D01*
X30730622Y71608991D01*
X30911831Y71427782D01*
X31054211Y71214695D01*
X31152284Y70977925D01*
X31202280Y70726579D01*
X31202280Y70470301D01*
X31152284Y70218955D01*
X31054211Y69982185D01*
X30911831Y69769098D01*
X30730622Y69587889D01*
X30730619Y69587887D01*
X30517535Y69445509D01*
X30280768Y69347437D01*
X30280767Y69347437D01*
X30280765Y69347436D01*
X30029419Y69297440D01*
X29773141Y69297440D01*
X29521795Y69347436D01*
X29521793Y69347437D01*
X29521792Y69347437D01*
X29285025Y69445509D01*
X29071941Y69587887D01*
X29071938Y69587889D01*
X28890729Y69769098D01*
X28748349Y69982185D01*
X28650276Y70218955D01*
X28600280Y70470301D01*
X28600280Y70726579D01*
X28650276Y70977925D01*
X28748349Y71214695D01*
X28890729Y71427782D01*
X29071938Y71608991D01*
X29285025Y71751371D01*
X29521792Y71849443D01*
X29521793Y71849443D01*
X29521795Y71849444D01*
X29773141Y71899440D01*
X30029419Y71899440D01*
X30280765Y71849444D01*
X30280765Y71849444D01*
G37*
G36*
X6480765Y71849444D02*
X6480767Y71849443D01*
X6480768Y71849443D01*
X6717535Y71751371D01*
X6930622Y71608991D01*
X7111831Y71427782D01*
X7254211Y71214695D01*
X7352284Y70977925D01*
X7402280Y70726579D01*
X7402280Y70470301D01*
X7352284Y70218955D01*
X7254211Y69982185D01*
X7111831Y69769098D01*
X6930622Y69587889D01*
X6930619Y69587887D01*
X6717535Y69445509D01*
X6480768Y69347437D01*
X6480767Y69347437D01*
X6480765Y69347436D01*
X6229419Y69297440D01*
X5973141Y69297440D01*
X5721795Y69347436D01*
X5721793Y69347437D01*
X5721792Y69347437D01*
X5485025Y69445509D01*
X5271941Y69587887D01*
X5271938Y69587889D01*
X5090729Y69769098D01*
X4948349Y69982185D01*
X4850276Y70218955D01*
X4800280Y70470301D01*
X4800280Y70726579D01*
X4850276Y70977925D01*
X4948349Y71214695D01*
X5090729Y71427782D01*
X5271938Y71608991D01*
X5485025Y71751371D01*
X5721792Y71849443D01*
X5721793Y71849443D01*
X5721795Y71849444D01*
X5973141Y71899440D01*
X6229419Y71899440D01*
X6480765Y71849444D01*
X6480765Y71849444D01*
G37*
G36*
X57203825Y85259260D02*
X58578018Y84690050D01*
X58578020Y84690049D01*
X59124085Y84325180D01*
X59814765Y83863683D01*
X60866523Y82811925D01*
X60866525Y82811922D01*
X61488636Y81880867D01*
X61692890Y81575178D01*
X62262100Y80200985D01*
X62552280Y78742150D01*
X62552280Y77254730D01*
X62262100Y75795895D01*
X61795864Y74670303D01*
X61692889Y74421700D01*
X61108725Y73547436D01*
X60866523Y73184955D01*
X59814765Y72133197D01*
X59814762Y72133195D01*
X58578020Y71306831D01*
X58578019Y71306830D01*
X58578018Y71306830D01*
X57203825Y70737620D01*
X55744990Y70447440D01*
X54257570Y70447440D01*
X52798735Y70737620D01*
X51424542Y71306830D01*
X51424541Y71306830D01*
X51424540Y71306831D01*
X50187798Y72133195D01*
X50187795Y72133197D01*
X49136037Y73184955D01*
X48893835Y73547436D01*
X48309671Y74421700D01*
X48206696Y74670303D01*
X47740460Y75795895D01*
X47450280Y77254730D01*
X47450280Y78742150D01*
X47740460Y80200985D01*
X48309670Y81575178D01*
X48513925Y81880867D01*
X49136035Y82811922D01*
X49136037Y82811925D01*
X50187795Y83863683D01*
X50878475Y84325180D01*
X51424540Y84690049D01*
X51424542Y84690050D01*
X52798735Y85259260D01*
X54257570Y85549440D01*
X55744990Y85549440D01*
X57203825Y85259260D01*
X57203825Y85259260D01*
G37*
G36*
X117203825Y88009260D02*
X118560177Y87447440D01*
X118578020Y87440049D01*
X119798314Y86624675D01*
X119814765Y86613683D01*
X120866523Y85561925D01*
X120866525Y85561922D01*
X121462519Y84669954D01*
X121692890Y84325178D01*
X122262100Y82950985D01*
X122552280Y81492150D01*
X122552280Y80004730D01*
X122262100Y78545895D01*
X121692890Y77171702D01*
X120866523Y75934955D01*
X119814765Y74883197D01*
X119814762Y74883195D01*
X118578020Y74056831D01*
X118578019Y74056830D01*
X118578018Y74056830D01*
X117203825Y73487620D01*
X115744990Y73197440D01*
X114257570Y73197440D01*
X112798735Y73487620D01*
X111424542Y74056830D01*
X111424541Y74056830D01*
X111424540Y74056831D01*
X110187798Y74883195D01*
X110187795Y74883197D01*
X109136037Y75934955D01*
X108309670Y77171702D01*
X107740460Y78545895D01*
X107450280Y80004730D01*
X107450280Y81492150D01*
X107740460Y82950985D01*
X108309670Y84325178D01*
X108540042Y84669954D01*
X109136035Y85561922D01*
X109136037Y85561925D01*
X110187795Y86613683D01*
X110204246Y86624675D01*
X111424540Y87440049D01*
X111442383Y87447440D01*
X112798735Y88009260D01*
X114257570Y88299440D01*
X115744990Y88299440D01*
X117203825Y88009260D01*
X117203825Y88009260D01*
G37*
G36*
X26080765Y76049444D02*
X26080767Y76049443D01*
X26080768Y76049443D01*
X26317535Y75951371D01*
X26530622Y75808991D01*
X26711831Y75627782D01*
X26854211Y75414695D01*
X26952284Y75177925D01*
X27002280Y74926579D01*
X27002280Y74670301D01*
X26952284Y74418955D01*
X26854211Y74182185D01*
X26711831Y73969098D01*
X26530622Y73787889D01*
X26530619Y73787887D01*
X26317535Y73645509D01*
X26080768Y73547437D01*
X26080767Y73547437D01*
X26080765Y73547436D01*
X25829419Y73497440D01*
X25573141Y73497440D01*
X25321795Y73547436D01*
X25321793Y73547437D01*
X25321792Y73547437D01*
X25085025Y73645509D01*
X24871941Y73787887D01*
X24871938Y73787889D01*
X24690729Y73969098D01*
X24548349Y74182185D01*
X24450276Y74418955D01*
X24400280Y74670301D01*
X24400280Y74926579D01*
X24450276Y75177925D01*
X24548349Y75414695D01*
X24690729Y75627782D01*
X24871938Y75808991D01*
X25085025Y75951371D01*
X25321792Y76049443D01*
X25321793Y76049443D01*
X25321795Y76049444D01*
X25573141Y76099440D01*
X25829419Y76099440D01*
X26080765Y76049444D01*
X26080765Y76049444D01*
G37*
G36*
X30280765Y76049444D02*
X30280767Y76049443D01*
X30280768Y76049443D01*
X30517535Y75951371D01*
X30730622Y75808991D01*
X30911831Y75627782D01*
X31054211Y75414695D01*
X31152284Y75177925D01*
X31202280Y74926579D01*
X31202280Y74670301D01*
X31152284Y74418955D01*
X31054211Y74182185D01*
X30911831Y73969098D01*
X30730622Y73787889D01*
X30730619Y73787887D01*
X30517535Y73645509D01*
X30280768Y73547437D01*
X30280767Y73547437D01*
X30280765Y73547436D01*
X30029419Y73497440D01*
X29773141Y73497440D01*
X29521795Y73547436D01*
X29521793Y73547437D01*
X29521792Y73547437D01*
X29285025Y73645509D01*
X29071941Y73787887D01*
X29071938Y73787889D01*
X28890729Y73969098D01*
X28748349Y74182185D01*
X28650276Y74418955D01*
X28600280Y74670301D01*
X28600280Y74926579D01*
X28650276Y75177925D01*
X28748349Y75414695D01*
X28890729Y75627782D01*
X29071938Y75808991D01*
X29285025Y75951371D01*
X29521792Y76049443D01*
X29521793Y76049443D01*
X29521795Y76049444D01*
X29773141Y76099440D01*
X30029419Y76099440D01*
X30280765Y76049444D01*
X30280765Y76049444D01*
G37*
G36*
X10680765Y76049444D02*
X10680767Y76049443D01*
X10680768Y76049443D01*
X10917535Y75951371D01*
X11130622Y75808991D01*
X11311831Y75627782D01*
X11454211Y75414695D01*
X11552284Y75177925D01*
X11602280Y74926579D01*
X11602280Y74670301D01*
X11552284Y74418955D01*
X11454211Y74182185D01*
X11311831Y73969098D01*
X11130622Y73787889D01*
X11130619Y73787887D01*
X10917535Y73645509D01*
X10680768Y73547437D01*
X10680767Y73547437D01*
X10680765Y73547436D01*
X10429419Y73497440D01*
X10173141Y73497440D01*
X9921795Y73547436D01*
X9921793Y73547437D01*
X9921792Y73547437D01*
X9685025Y73645509D01*
X9471941Y73787887D01*
X9471938Y73787889D01*
X9290729Y73969098D01*
X9148349Y74182185D01*
X9050276Y74418955D01*
X9000280Y74670301D01*
X9000280Y74926579D01*
X9050276Y75177925D01*
X9148349Y75414695D01*
X9290729Y75627782D01*
X9471938Y75808991D01*
X9685025Y75951371D01*
X9921792Y76049443D01*
X9921793Y76049443D01*
X9921795Y76049444D01*
X10173141Y76099440D01*
X10429419Y76099440D01*
X10680765Y76049444D01*
X10680765Y76049444D01*
G37*
G36*
X6480765Y76049444D02*
X6480767Y76049443D01*
X6480768Y76049443D01*
X6717535Y75951371D01*
X6930622Y75808991D01*
X7111831Y75627782D01*
X7254211Y75414695D01*
X7352284Y75177925D01*
X7402280Y74926579D01*
X7402280Y74670301D01*
X7352284Y74418955D01*
X7254211Y74182185D01*
X7111831Y73969098D01*
X6930622Y73787889D01*
X6930619Y73787887D01*
X6717535Y73645509D01*
X6480768Y73547437D01*
X6480767Y73547437D01*
X6480765Y73547436D01*
X6229419Y73497440D01*
X5973141Y73497440D01*
X5721795Y73547436D01*
X5721793Y73547437D01*
X5721792Y73547437D01*
X5485025Y73645509D01*
X5271941Y73787887D01*
X5271938Y73787889D01*
X5090729Y73969098D01*
X4948349Y74182185D01*
X4850276Y74418955D01*
X4800280Y74670301D01*
X4800280Y74926579D01*
X4850276Y75177925D01*
X4948349Y75414695D01*
X5090729Y75627782D01*
X5271938Y75808991D01*
X5485025Y75951371D01*
X5721792Y76049443D01*
X5721793Y76049443D01*
X5721795Y76049444D01*
X5973141Y76099440D01*
X6229419Y76099440D01*
X6480765Y76049444D01*
X6480765Y76049444D01*
G37*
G36*
X10680765Y80249444D02*
X10680767Y80249443D01*
X10680768Y80249443D01*
X10797756Y80200985D01*
X10917535Y80151371D01*
X11130622Y80008991D01*
X11311831Y79827782D01*
X11454211Y79614695D01*
X11552284Y79377925D01*
X11602280Y79126579D01*
X11602280Y78870301D01*
X11552284Y78618955D01*
X11454211Y78382185D01*
X11311831Y78169098D01*
X11130622Y77987889D01*
X11130619Y77987887D01*
X10917535Y77845509D01*
X10680768Y77747437D01*
X10680767Y77747437D01*
X10680765Y77747436D01*
X10429419Y77697440D01*
X10173141Y77697440D01*
X9921795Y77747436D01*
X9921793Y77747437D01*
X9921792Y77747437D01*
X9685025Y77845509D01*
X9471941Y77987887D01*
X9471938Y77987889D01*
X9290729Y78169098D01*
X9148349Y78382185D01*
X9050276Y78618955D01*
X9000280Y78870301D01*
X9000280Y79126579D01*
X9050276Y79377925D01*
X9148349Y79614695D01*
X9290729Y79827782D01*
X9471938Y80008991D01*
X9685025Y80151371D01*
X9804804Y80200985D01*
X9921792Y80249443D01*
X9921793Y80249443D01*
X9921795Y80249444D01*
X10173141Y80299440D01*
X10429419Y80299440D01*
X10680765Y80249444D01*
X10680765Y80249444D01*
G37*
G36*
X6480765Y80249444D02*
X6480767Y80249443D01*
X6480768Y80249443D01*
X6597756Y80200985D01*
X6717535Y80151371D01*
X6930622Y80008991D01*
X7111831Y79827782D01*
X7254211Y79614695D01*
X7352284Y79377925D01*
X7402280Y79126579D01*
X7402280Y78870301D01*
X7352284Y78618955D01*
X7254211Y78382185D01*
X7111831Y78169098D01*
X6930622Y77987889D01*
X6930619Y77987887D01*
X6717535Y77845509D01*
X6480768Y77747437D01*
X6480767Y77747437D01*
X6480765Y77747436D01*
X6229419Y77697440D01*
X5973141Y77697440D01*
X5721795Y77747436D01*
X5721793Y77747437D01*
X5721792Y77747437D01*
X5485025Y77845509D01*
X5271941Y77987887D01*
X5271938Y77987889D01*
X5090729Y78169098D01*
X4948349Y78382185D01*
X4850276Y78618955D01*
X4800280Y78870301D01*
X4800280Y79126579D01*
X4850276Y79377925D01*
X4948349Y79614695D01*
X5090729Y79827782D01*
X5271938Y80008991D01*
X5485025Y80151371D01*
X5604804Y80200985D01*
X5721792Y80249443D01*
X5721793Y80249443D01*
X5721795Y80249444D01*
X5973141Y80299440D01*
X6229419Y80299440D01*
X6480765Y80249444D01*
X6480765Y80249444D01*
G37*
G36*
X26080765Y80249444D02*
X26080767Y80249443D01*
X26080768Y80249443D01*
X26197756Y80200985D01*
X26317535Y80151371D01*
X26530622Y80008991D01*
X26711831Y79827782D01*
X26854211Y79614695D01*
X26952284Y79377925D01*
X27002280Y79126579D01*
X27002280Y78870301D01*
X26952284Y78618955D01*
X26854211Y78382185D01*
X26711831Y78169098D01*
X26530622Y77987889D01*
X26530619Y77987887D01*
X26317535Y77845509D01*
X26080768Y77747437D01*
X26080767Y77747437D01*
X26080765Y77747436D01*
X25829419Y77697440D01*
X25573141Y77697440D01*
X25321795Y77747436D01*
X25321793Y77747437D01*
X25321792Y77747437D01*
X25085025Y77845509D01*
X24871941Y77987887D01*
X24871938Y77987889D01*
X24690729Y78169098D01*
X24548349Y78382185D01*
X24450276Y78618955D01*
X24400280Y78870301D01*
X24400280Y79126579D01*
X24450276Y79377925D01*
X24548349Y79614695D01*
X24690729Y79827782D01*
X24871938Y80008991D01*
X25085025Y80151371D01*
X25204804Y80200985D01*
X25321792Y80249443D01*
X25321793Y80249443D01*
X25321795Y80249444D01*
X25573141Y80299440D01*
X25829419Y80299440D01*
X26080765Y80249444D01*
X26080765Y80249444D01*
G37*
G36*
X30280765Y80249444D02*
X30280767Y80249443D01*
X30280768Y80249443D01*
X30397756Y80200985D01*
X30517535Y80151371D01*
X30730622Y80008991D01*
X30911831Y79827782D01*
X31054211Y79614695D01*
X31152284Y79377925D01*
X31202280Y79126579D01*
X31202280Y78870301D01*
X31152284Y78618955D01*
X31054211Y78382185D01*
X30911831Y78169098D01*
X30730622Y77987889D01*
X30730619Y77987887D01*
X30517535Y77845509D01*
X30280768Y77747437D01*
X30280767Y77747437D01*
X30280765Y77747436D01*
X30029419Y77697440D01*
X29773141Y77697440D01*
X29521795Y77747436D01*
X29521793Y77747437D01*
X29521792Y77747437D01*
X29285025Y77845509D01*
X29071941Y77987887D01*
X29071938Y77987889D01*
X28890729Y78169098D01*
X28748349Y78382185D01*
X28650276Y78618955D01*
X28600280Y78870301D01*
X28600280Y79126579D01*
X28650276Y79377925D01*
X28748349Y79614695D01*
X28890729Y79827782D01*
X29071938Y80008991D01*
X29285025Y80151371D01*
X29404804Y80200985D01*
X29521792Y80249443D01*
X29521793Y80249443D01*
X29521795Y80249444D01*
X29773141Y80299440D01*
X30029419Y80299440D01*
X30280765Y80249444D01*
X30280765Y80249444D01*
G37*
G36*
X6499532Y85670622D02*
X6499534Y85670621D01*
X6499535Y85670621D01*
X6872793Y85516013D01*
X6872794Y85516012D01*
X7208719Y85291554D01*
X7494394Y85005879D01*
X7494396Y85005876D01*
X7718853Y84669953D01*
X7873461Y84296695D01*
X7952280Y83900446D01*
X7952280Y83496434D01*
X7873461Y83100185D01*
X7718853Y82726927D01*
X7718852Y82726926D01*
X7494394Y82391001D01*
X7208719Y82105326D01*
X7208716Y82105324D01*
X6872793Y81880867D01*
X6499535Y81726259D01*
X6499534Y81726259D01*
X6499532Y81726258D01*
X6103287Y81647440D01*
X5699273Y81647440D01*
X5303028Y81726258D01*
X5303026Y81726259D01*
X5303025Y81726259D01*
X4929767Y81880867D01*
X4593844Y82105324D01*
X4593841Y82105326D01*
X4308166Y82391001D01*
X4083708Y82726926D01*
X4083707Y82726927D01*
X3929099Y83100185D01*
X3850280Y83496434D01*
X3850280Y83900446D01*
X3929099Y84296695D01*
X4083707Y84669953D01*
X4308164Y85005876D01*
X4308166Y85005879D01*
X4593841Y85291554D01*
X4929766Y85516012D01*
X4929767Y85516013D01*
X5303025Y85670621D01*
X5303026Y85670621D01*
X5303028Y85670622D01*
X5699273Y85749440D01*
X6103287Y85749440D01*
X6499532Y85670622D01*
X6499532Y85670622D01*
G37*
G36*
X30699532Y85670622D02*
X30699534Y85670621D01*
X30699535Y85670621D01*
X31072793Y85516013D01*
X31072794Y85516012D01*
X31408719Y85291554D01*
X31694394Y85005879D01*
X31694396Y85005876D01*
X31918853Y84669953D01*
X32073461Y84296695D01*
X32152280Y83900446D01*
X32152280Y83496434D01*
X32073461Y83100185D01*
X31918853Y82726927D01*
X31918852Y82726926D01*
X31694394Y82391001D01*
X31408719Y82105326D01*
X31408716Y82105324D01*
X31072793Y81880867D01*
X30699535Y81726259D01*
X30699534Y81726259D01*
X30699532Y81726258D01*
X30303287Y81647440D01*
X29899273Y81647440D01*
X29503028Y81726258D01*
X29503026Y81726259D01*
X29503025Y81726259D01*
X29129767Y81880867D01*
X28793844Y82105324D01*
X28793841Y82105326D01*
X28508166Y82391001D01*
X28283708Y82726926D01*
X28283707Y82726927D01*
X28129099Y83100185D01*
X28050280Y83496434D01*
X28050280Y83900446D01*
X28129099Y84296695D01*
X28283707Y84669953D01*
X28508164Y85005876D01*
X28508166Y85005879D01*
X28793841Y85291554D01*
X29129766Y85516012D01*
X29129767Y85516013D01*
X29503025Y85670621D01*
X29503026Y85670621D01*
X29503028Y85670622D01*
X29899273Y85749440D01*
X30303287Y85749440D01*
X30699532Y85670622D01*
X30699532Y85670622D01*
G37*
G36*
X140745376Y92451407D02*
X140745378Y92451406D01*
X140745379Y92451406D01*
X141209632Y92259107D01*
X141625564Y91981190D01*
X141627451Y91979929D01*
X141982769Y91624611D01*
X141982771Y91624608D01*
X142261947Y91206792D01*
X142454246Y90742539D01*
X142552280Y90249692D01*
X142552280Y89747188D01*
X142454246Y89254341D01*
X142261947Y88790088D01*
X141984030Y88374156D01*
X141982769Y88372269D01*
X141627451Y88016951D01*
X141627448Y88016949D01*
X141209632Y87737773D01*
X140745379Y87545474D01*
X140745378Y87545474D01*
X140745376Y87545473D01*
X140252533Y87447440D01*
X139750027Y87447440D01*
X139257184Y87545473D01*
X139257182Y87545474D01*
X139257181Y87545474D01*
X138792928Y87737773D01*
X138375112Y88016949D01*
X138375109Y88016951D01*
X138019791Y88372269D01*
X138018530Y88374156D01*
X137740613Y88790088D01*
X137548314Y89254341D01*
X137450280Y89747188D01*
X137450280Y90249692D01*
X137548314Y90742539D01*
X137740613Y91206792D01*
X138019789Y91624608D01*
X138019791Y91624611D01*
X138375109Y91979929D01*
X138376996Y91981190D01*
X138792928Y92259107D01*
X139257181Y92451406D01*
X139257182Y92451406D01*
X139257184Y92451407D01*
X139750027Y92549440D01*
X140252533Y92549440D01*
X140745376Y92451407D01*
X140745376Y92451407D01*
G37*
G36*
X745376Y92451407D02*
X745378Y92451406D01*
X745379Y92451406D01*
X1209632Y92259107D01*
X1625564Y91981190D01*
X1627451Y91979929D01*
X1982769Y91624611D01*
X1982771Y91624608D01*
X2261947Y91206792D01*
X2454246Y90742539D01*
X2552280Y90249692D01*
X2552280Y89747188D01*
X2454246Y89254341D01*
X2261947Y88790088D01*
X1984030Y88374156D01*
X1982769Y88372269D01*
X1627451Y88016951D01*
X1627448Y88016949D01*
X1209632Y87737773D01*
X745379Y87545474D01*
X745378Y87545474D01*
X745376Y87545473D01*
X252533Y87447440D01*
X-249973Y87447440D01*
X-742816Y87545473D01*
X-742818Y87545474D01*
X-742819Y87545474D01*
X-1207072Y87737773D01*
X-1624888Y88016949D01*
X-1624891Y88016951D01*
X-1980209Y88372269D01*
X-1981470Y88374156D01*
X-2259387Y88790088D01*
X-2451686Y89254341D01*
X-2549720Y89747188D01*
X-2549720Y90249692D01*
X-2451686Y90742539D01*
X-2259387Y91206792D01*
X-1980211Y91624608D01*
X-1980209Y91624611D01*
X-1624891Y91979929D01*
X-1623004Y91981190D01*
X-1207072Y92259107D01*
X-742819Y92451406D01*
X-742818Y92451406D01*
X-742816Y92451407D01*
X-249973Y92549440D01*
X252533Y92549440D01*
X745376Y92451407D01*
X745376Y92451407D01*
G37*
M02*
